# BASEBOARD_FAB2 (Tioga Pass) — schematic netlist excerpt (pin names and nets, part order shuffled) for the footprints in the layout excerpt that follows; sources: Cadence DE-HDL packaged netlist, KiCad conversion of Wiwynn_Tioga_Pass_MB.brd

R1T11  RES  1.00K 1% CHIP  pkg 0402  page 164 : A = FM_BOARD_REV_ID2 ; B = GND
R7F6  RES  4.75K 1% EMPTY  pkg 0402  page 153 : A = P3V3_STBY ; B = PU_SPI0_RST
R2U51  RES  0.0 5% EMPTY  pkg 0402  page 152 : A = H_CPU0_MEMABC_MEMHOT_G_PCH_N ; B = H_CPU0_MEMABC_MEMHOT_G_N

(kicad_pcb
	(version 20260206)
	(generator "pcbnew")
	(generator_version "10.0")
	(general
		(thickness 1.6)
		(legacy_teardrops no)
	)
	(paper "A4")
	(title_block
		(title "Wiwynn_Tioga_Pass_MB.brd")
		(comment 1 "Tioga Pass / footprints 157-159 of 4770")
	)
	(layers
		(0 "F.Cu" signal "TOP")
		(4 "In1.Cu" signal "L2GND")
		(6 "In2.Cu" signal "L3")
		(8 "In3.Cu" signal "L4GND")
		(10 "In4.Cu" signal "L5")
		(12 "In5.Cu" signal "L6GND")
		(14 "In6.Cu" signal "L7VCC")
		(16 "In7.Cu" signal "L8VCC")
		(18 "In8.Cu" signal "L9GND")
		(20 "In9.Cu" signal "L10")
		(22 "In10.Cu" signal "L11GND")
		(24 "In11.Cu" signal "L12")
		(26 "In12.Cu" signal "L13GND")
		(2 "B.Cu" signal "BOTTOM")
		(9 "F.Adhes" user "F.Adhesive")
		(11 "B.Adhes" user "B.Adhesive")
		(13 "F.Paste" user "Package Geometry/Pastemask Top")
		(15 "B.Paste" user "Package Geometry/Pastemask Bottom")
		(5 "F.SilkS" user "Ref Des/Silkscreen Top")
		(7 "B.SilkS" user "Ref Des/Silkscreen Bottom")
		(1 "F.Mask" user "Board Geometry/Soldermask Top")
		(3 "B.Mask" user "Board Geometry/Soldermask Bottom")
		(17 "Dwgs.User" user "User.Drawings")
		(19 "Cmts.User" user "User.Comments")
		(21 "Eco1.User" user "User.Eco1")
		(23 "Eco2.User" user "User.Eco2")
		(25 "Edge.Cuts" user "Board Geometry/Outline")
		(27 "Margin" user)
		(31 "F.CrtYd" user "Package Geometry/Place Bound Top")
		(29 "B.CrtYd" user "Package Geometry/Place Bound Bottom")
		(35 "F.Fab" user "Ref Des/Assembly Top")
		(33 "B.Fab" user "Ref Des/Assembly Bottom")
	)
	(footprint ""
		(layer "F.Cu")
		(at 409.685236 -47.825914 180)
		(property "Reference" "R1T11"
			(at 0 0 180)
			(layer "F.SilkS")
			(hide yes)
			(effects
				(font
					(size 1.27 1.27)
				)
			)
		)
		(property "Value" ""
			(at 0 0 180)
			(layer "F.Fab")
			(effects
				(font
					(size 1.27 1.27)
				)
			)
		)
		(duplicate_pad_numbers_are_jumpers no)
		(fp_poly
			(pts
				(xy -0.2794 -0.1016) (xy 0.2794 -0.1016) (xy 0.2794 0.9906) (xy -0.2794 0.9906)
			)
			(stroke
				(width 0)
				(type default)
			)
			(fill no)
			(layer "F.CrtYd")
		)
		(fp_line
			(start 0.2794 0.9906)
			(end 0.2794 -0.1016)
			(stroke
				(width 0.1)
				(type default)
			)
			(layer "F.Fab")
		)
		(fp_line
			(start 0.2794 -0.1016)
			(end -0.2794 -0.1016)
			(stroke
				(width 0.1)
				(type default)
			)
			(layer "F.Fab")
		)
		(fp_line
			(start -0.2794 0.9906)
			(end 0.2794 0.9906)
			(stroke
				(width 0.1)
				(type default)
			)
			(layer "F.Fab")
		)
		(fp_line
			(start -0.2794 -0.1016)
			(end -0.2794 0.9906)
			(stroke
				(width 0.1)
				(type default)
			)
			(layer "F.Fab")
		)
		(pad "1" smd rect
			(at 0 0 180)
			(size 0.508 0.508)
			(layers "F.Cu" "F.Mask" "F.Paste")
			(net "FM_BOARD_REV_ID2")
		)
		(pad "2" smd rect
			(at 0 0.889 180)
			(size 0.508 0.508)
			(layers "F.Cu" "F.Mask" "F.Paste")
			(net "GND")
		)
	)
	(footprint ""
		(layer "F.Cu")
		(at 442.364876 -13.361924 90)
		(property "Reference" "R2U51"
			(at 0 0 90)
			(layer "F.SilkS")
			(hide yes)
			(effects
				(font
					(size 1.27 1.27)
				)
			)
		)
		(property "Value" ""
			(at 0 0 90)
			(layer "F.Fab")
			(effects
				(font
					(size 1.27 1.27)
				)
			)
		)
		(duplicate_pad_numbers_are_jumpers no)
		(fp_poly
			(pts
				(xy -0.2794 -0.1016) (xy 0.2794 -0.1016) (xy 0.2794 0.9906) (xy -0.2794 0.9906)
			)
			(stroke
				(width 0)
				(type default)
			)
			(fill no)
			(layer "F.CrtYd")
		)
		(fp_line
			(start 0.2794 -0.1016)
			(end -0.2794 -0.1016)
			(stroke
				(width 0.1)
				(type default)
			)
			(layer "F.Fab")
		)
		(fp_line
			(start -0.2794 -0.1016)
			(end -0.2794 0.9906)
			(stroke
				(width 0.1)
				(type default)
			)
			(layer "F.Fab")
		)
		(fp_line
			(start 0.2794 0.9906)
			(end 0.2794 -0.1016)
			(stroke
				(width 0.1)
				(type default)
			)
			(layer "F.Fab")
		)
		(fp_line
			(start -0.2794 0.9906)
			(end 0.2794 0.9906)
			(stroke
				(width 0.1)
				(type default)
			)
			(layer "F.Fab")
		)
		(pad "1" smd rect
			(at 0 0 90)
			(size 0.508 0.508)
			(layers "F.Cu" "F.Mask" "F.Paste")
			(net "H_CPU0_MEMABC_MEMHOT_G_PCH_N")
		)
		(pad "2" smd rect
			(at 0 0.889 90)
			(size 0.508 0.508)
			(layers "F.Cu" "F.Mask" "F.Paste")
			(net "H_CPU0_MEMABC_MEMHOT_G_N")
		)
		(zone
			(layer "F.Cu")
			(hatch none 0.5)
			(connect_pads
				(clearance 0)
			)
			(min_thickness 0.25)
			(keepout
				(tracks allowed)
				(vias not_allowed)
				(pads allowed)
				(copperpour not_allowed)
				(footprints allowed)
			)
			(placement
				(enabled no)
				(sheetname "")
			)
			(fill
				(thermal_gap 0.5)
				(thermal_bridge_width 0.5)
				(island_removal_mode 0)
			)
			(polygon
				(pts
					(xy 442.618876 -13.107924) (xy 442.618876 -13.615924) (xy 442.999876 -13.615924) (xy 442.999876 -13.107924)
				)
			)
		)
		(zone
			(layer "F.Cu")
			(hatch none 0.5)
			(connect_pads
				(clearance 0)
			)
			(min_thickness 0.25)
			(keepout
				(tracks not_allowed)
				(vias allowed)
				(pads allowed)
				(copperpour not_allowed)
				(footprints allowed)
			)
			(placement
				(enabled no)
				(sheetname "")
			)
			(fill
				(thermal_gap 0.5)
				(thermal_bridge_width 0.5)
				(island_removal_mode 0)
			)
			(polygon
				(pts
					(xy 442.999876 -13.107924) (xy 442.999876 -13.615924) (xy 442.618876 -13.615924) (xy 442.618876 -13.107924)
				)
			)
		)
	)
	(footprint ""
		(layer "F.Cu")
		(at 401.066 -49.0855 180)
		(property "Reference" "R7F6"
			(at 0 0 180)
			(layer "F.SilkS")
			(hide yes)
			(effects
				(font
					(size 1.27 1.27)
				)
			)
		)
		(property "Value" ""
			(at 0 0 180)
			(layer "F.Fab")
			(effects
				(font
					(size 1.27 1.27)
				)
			)
		)
		(duplicate_pad_numbers_are_jumpers no)
		(fp_poly
			(pts
				(xy -0.2794 -0.1016) (xy 0.2794 -0.1016) (xy 0.2794 0.9906) (xy -0.2794 0.9906)
			)
			(stroke
				(width 0)
				(type default)
			)
			(fill no)
			(layer "F.CrtYd")
		)
		(fp_line
			(start 0.2794 0.9906)
			(end 0.2794 -0.1016)
			(stroke
				(width 0.1)
				(type default)
			)
			(layer "F.Fab")
		)
		(fp_line
			(start 0.2794 -0.1016)
			(end -0.2794 -0.1016)
			(stroke
				(width 0.1)
				(type default)
			)
			(layer "F.Fab")
		)
		(fp_line
			(start -0.2794 0.9906)
			(end 0.2794 0.9906)
			(stroke
				(width 0.1)
				(type default)
			)
			(layer "F.Fab")
		)
		(fp_line
			(start -0.2794 -0.1016)
			(end -0.2794 0.9906)
			(stroke
				(width 0.1)
				(type default)
			)
			(layer "F.Fab")
		)
		(pad "1" smd rect
			(at 0 0 180)
			(size 0.508 0.508)
			(layers "F.Cu" "F.Mask" "F.Paste")
			(net "P3V3_STBY")
		)
		(pad "2" smd rect
			(at 0 0.889 180)
			(size 0.508 0.508)
			(layers "F.Cu" "F.Mask" "F.Paste")
			(net "PU_SPI0_RST")
		)
		(zone
			(layer "F.Cu")
			(hatch none 0.5)
			(connect_pads
				(clearance 0)
			)
			(min_thickness 0.25)
			(keepout
				(tracks not_allowed)
				(vias allowed)
				(pads allowed)
				(copperpour not_allowed)
				(footprints allowed)
			)
			(placement
				(enabled no)
				(sheetname "")
			)
			(fill
				(thermal_gap 0.5)
				(thermal_bridge_width 0.5)
				(island_removal_mode 0)
			)
			(polygon
				(pts
					(xy 401.32 -49.7205) (xy 400.812 -49.7205) (xy 400.812 -49.3395) (xy 401.32 -49.3395)
				)
			)
		)
		(zone
			(layer "F.Cu")
			(hatch none 0.5)
			(connect_pads
				(clearance 0)
			)
			(min_thickness 0.25)
			(keepout
				(tracks allowed)
				(vias not_allowed)
				(pads allowed)
				(copperpour not_allowed)
				(footprints allowed)
			)
			(placement
				(enabled no)
				(sheetname "")
			)
			(fill
				(thermal_gap 0.5)
				(thermal_bridge_width 0.5)
				(island_removal_mode 0)
			)
			(polygon
				(pts
					(xy 401.32 -49.3395) (xy 400.812 -49.3395) (xy 400.812 -49.7205) (xy 401.32 -49.7205)
				)
			)
		)
	)
)
